# T6G (Grand Teton) — schematic netlist excerpt (pin names and nets, part order shuffled) for the footprints in the layout excerpt that follows; sources: Cadence DE-HDL packaged netlist, KiCad conversion of 04192023_DAF0TMB3IC0_F0TG_MB_C_brd_V02_OCP.brd

PR115  Q_RES  49.9 1% CHIP  pkg 0402LF  page 207 : A = VSENSE_VSS_SENSE_C_P0 ; B = GND
C914  Q_CAP_DIFFBUS  DIFF BUS_0.22UF 6.3V 20% X6S  pkg C0201  page 63 : \1\ = P5E_CPU0_P0_TX_C_DN<9> ; \2\ = P5E_CPU0_P0_TX_DN<9>
R1071  Q_RES  4.7K 5% EMPTY  pkg 0402LF  page 83 : A = P3V3_OCP_SFF_EN_R ; B = P3V3_AUX

(kicad_pcb
	(version 20260206)
	(generator "pcbnew")
	(generator_version "10.0")
	(general
		(thickness 1.6)
		(legacy_teardrops no)
	)
	(paper "A4")
	(title_block
		(title "04192023_DAF0TMB3IC0_F0TG_MB_C_brd_V02_OCP.brd")
		(comment 1 "Grand Teton / footprints 439-441 of 8354")
	)
	(layers
		(0 "F.Cu" signal "TOP")
		(4 "In1.Cu" signal "GND")
		(6 "In2.Cu" signal "IN1")
		(8 "In3.Cu" signal "GND1")
		(10 "In4.Cu" signal "IN2")
		(12 "In5.Cu" signal "GND2")
		(14 "In6.Cu" signal "IN3")
		(16 "In7.Cu" signal "GND3")
		(18 "In8.Cu" signal "VCC")
		(20 "In9.Cu" signal "VCC1")
		(22 "In10.Cu" signal "GND4")
		(24 "In11.Cu" signal "IN4")
		(26 "In12.Cu" signal "GND5")
		(28 "In13.Cu" signal "IN5")
		(30 "In14.Cu" signal "GND6")
		(32 "In15.Cu" signal "IN6")
		(34 "In16.Cu" signal "GND7")
		(2 "B.Cu" signal "BOTTOM")
		(9 "F.Adhes" user "F.Adhesive")
		(11 "B.Adhes" user "B.Adhesive")
		(13 "F.Paste" user "Package Geometry/Pastemask Top")
		(15 "B.Paste" user "Package Geometry/Pastemask Bottom")
		(5 "F.SilkS" user "Ref Des/Silkscreen Top")
		(7 "B.SilkS" user "Ref Des/Silkscreen Bottom")
		(1 "F.Mask" user "Board Geometry/Soldermask Top")
		(3 "B.Mask" user "Board Geometry/Soldermask Bottom")
		(17 "Dwgs.User" user "User.Drawings")
		(19 "Cmts.User" user "User.Comments")
		(21 "Eco1.User" user "User.Eco1")
		(23 "Eco2.User" user "User.Eco2")
		(25 "Edge.Cuts" user "Board Geometry/Outline")
		(27 "Margin" user)
		(31 "F.CrtYd" user "Package Geometry/Place Bound Top")
		(29 "B.CrtYd" user "Package Geometry/Place Bound Bottom")
		(35 "F.Fab" user "Ref Des/Assembly Top")
		(33 "B.Fab" user "Ref Des/Assembly Bottom")
	)
	(footprint ""
		(layer "F.Cu")
		(at 315.220096 -378.95403 -90)
		(property "Reference" "C914"
			(at 0 0 270)
			(layer "F.SilkS")
			(hide yes)
			(effects
				(font
					(size 1.27 1.27)
				)
			)
		)
		(property "Value" ""
			(at 0 0 270)
			(layer "F.Fab")
			(effects
				(font
					(size 1.27 1.27)
				)
			)
		)
		(duplicate_pad_numbers_are_jumpers no)
		(fp_line
			(start -0.299974 0.150114)
			(end -0.299974 -0.150114)
			(stroke
				(width 0.1)
				(type default)
			)
			(layer "F.Fab")
		)
		(fp_line
			(start 0.299974 0.150114)
			(end -0.299974 0.150114)
			(stroke
				(width 0.1)
				(type default)
			)
			(layer "F.Fab")
		)
		(fp_line
			(start -0.299974 -0.150114)
			(end 0.299974 -0.150114)
			(stroke
				(width 0.1)
				(type default)
			)
			(layer "F.Fab")
		)
		(fp_line
			(start 0.299974 -0.150114)
			(end 0.299974 0.150114)
			(stroke
				(width 0.1)
				(type default)
			)
			(layer "F.Fab")
		)
		(pad "1" smd rect
			(at -0.2667 0 270)
			(size 0.3048 0.381)
			(layers "F.Cu" "F.Mask" "F.Paste")
			(net "P5E_CPU0_P0_TX_C_DN<9>")
		)
		(pad "2" smd rect
			(at 0.2667 0 270)
			(size 0.3048 0.381)
			(layers "F.Cu" "F.Mask" "F.Paste")
			(net "P5E_CPU0_P0_TX_DN<9>")
		)
	)
	(footprint ""
		(layer "F.Cu")
		(at 415.628582 -331.945996)
		(property "Reference" "PR115"
			(at 0 0 0)
			(layer "F.SilkS")
			(hide yes)
			(effects
				(font
					(size 1.27 1.27)
				)
			)
		)
		(property "Value" ""
			(at 0 0 0)
			(layer "F.Fab")
			(effects
				(font
					(size 1.27 1.27)
				)
			)
		)
		(duplicate_pad_numbers_are_jumpers no)
		(fp_line
			(start -0.7874 -0.4064)
			(end 0.7874 -0.4064)
			(stroke
				(width 0.1524)
				(type default)
			)
			(layer "F.SilkS")
		)
		(fp_line
			(start -0.7874 0.4064)
			(end -0.7874 -0.4064)
			(stroke
				(width 0.1524)
				(type default)
			)
			(layer "F.SilkS")
		)
		(fp_line
			(start 0.7874 -0.4064)
			(end 0.7874 0.4064)
			(stroke
				(width 0.1524)
				(type default)
			)
			(layer "F.SilkS")
		)
		(fp_line
			(start 0.7874 0.4064)
			(end -0.7874 0.4064)
			(stroke
				(width 0.1524)
				(type default)
			)
			(layer "F.SilkS")
		)
		(fp_line
			(start -0.67945 -0.305054)
			(end -0.12065 -0.305054)
			(stroke
				(width 0.1)
				(type default)
			)
			(layer "F.Fab")
		)
		(fp_line
			(start -0.67945 0.3048)
			(end -0.67945 -0.305054)
			(stroke
				(width 0.1)
				(type default)
			)
			(layer "F.Fab")
		)
		(fp_line
			(start -0.12065 -0.305054)
			(end -0.12065 -0.2794)
			(stroke
				(width 0.1)
				(type default)
			)
			(layer "F.Fab")
		)
		(fp_line
			(start -0.12065 -0.2794)
			(end 0.12065 -0.2794)
			(stroke
				(width 0.1)
				(type default)
			)
			(layer "F.Fab")
		)
		(fp_line
			(start -0.12065 0.2794)
			(end -0.12065 0.3048)
			(stroke
				(width 0.1)
				(type default)
			)
			(layer "F.Fab")
		)
		(fp_line
			(start -0.12065 0.3048)
			(end -0.67945 0.3048)
			(stroke
				(width 0.1)
				(type default)
			)
			(layer "F.Fab")
		)
		(fp_line
			(start 0.120396 0.2794)
			(end -0.12065 0.2794)
			(stroke
				(width 0.1)
				(type default)
			)
			(layer "F.Fab")
		)
		(fp_line
			(start 0.120396 0.3048)
			(end 0.120396 0.2794)
			(stroke
				(width 0.1)
				(type default)
			)
			(layer "F.Fab")
		)
		(fp_line
			(start 0.12065 -0.3048)
			(end 0.67945 -0.3048)
			(stroke
				(width 0.1)
				(type default)
			)
			(layer "F.Fab")
		)
		(fp_line
			(start 0.12065 -0.2794)
			(end 0.12065 -0.3048)
			(stroke
				(width 0.1)
				(type default)
			)
			(layer "F.Fab")
		)
		(fp_line
			(start 0.67945 -0.3048)
			(end 0.67945 0.3048)
			(stroke
				(width 0.1)
				(type default)
			)
			(layer "F.Fab")
		)
		(fp_line
			(start 0.67945 0.3048)
			(end 0.120396 0.3048)
			(stroke
				(width 0.1)
				(type default)
			)
			(layer "F.Fab")
		)
		(pad "1" smd circle
			(at -0.40005 0)
			(size 0 0)
			(layers "F.Cu" "F.Mask" "F.Paste")
			(net "VSENSE_VSS_SENSE_C_P0")
		)
		(pad "2" smd circle
			(at 0.40005 0)
			(size 0 0)
			(layers "F.Cu" "F.Mask" "F.Paste")
			(net "GND")
		)
	)
	(footprint ""
		(layer "F.Cu")
		(at 163.703 -112.359948 180)
		(property "Reference" "R1071"
			(at 0 0 180)
			(layer "F.SilkS")
			(hide yes)
			(effects
				(font
					(size 1.27 1.27)
				)
			)
		)
		(property "Value" ""
			(at 0 0 180)
			(layer "F.Fab")
			(effects
				(font
					(size 1.27 1.27)
				)
			)
		)
		(duplicate_pad_numbers_are_jumpers no)
		(fp_line
			(start 0.7874 0.4064)
			(end -0.7874 0.4064)
			(stroke
				(width 0.1524)
				(type default)
			)
			(layer "F.SilkS")
		)
		(fp_line
			(start 0.7874 -0.4064)
			(end 0.7874 0.4064)
			(stroke
				(width 0.1524)
				(type default)
			)
			(layer "F.SilkS")
		)
		(fp_line
			(start -0.7874 0.4064)
			(end -0.7874 -0.4064)
			(stroke
				(width 0.1524)
				(type default)
			)
			(layer "F.SilkS")
		)
		(fp_line
			(start -0.7874 -0.4064)
			(end 0.7874 -0.4064)
			(stroke
				(width 0.1524)
				(type default)
			)
			(layer "F.SilkS")
		)
		(fp_line
			(start 0.67945 0.3048)
			(end 0.120396 0.3048)
			(stroke
				(width 0.1)
				(type default)
			)
			(layer "F.Fab")
		)
		(fp_line
			(start 0.67945 -0.3048)
			(end 0.67945 0.3048)
			(stroke
				(width 0.1)
				(type default)
			)
			(layer "F.Fab")
		)
		(fp_line
			(start 0.12065 -0.2794)
			(end 0.12065 -0.3048)
			(stroke
				(width 0.1)
				(type default)
			)
			(layer "F.Fab")
		)
		(fp_line
			(start 0.12065 -0.3048)
			(end 0.67945 -0.3048)
			(stroke
				(width 0.1)
				(type default)
			)
			(layer "F.Fab")
		)
		(fp_line
			(start 0.120396 0.3048)
			(end 0.120396 0.2794)
			(stroke
				(width 0.1)
				(type default)
			)
			(layer "F.Fab")
		)
		(fp_line
			(start 0.120396 0.2794)
			(end -0.12065 0.2794)
			(stroke
				(width 0.1)
				(type default)
			)
			(layer "F.Fab")
		)
		(fp_line
			(start -0.12065 0.3048)
			(end -0.67945 0.3048)
			(stroke
				(width 0.1)
				(type default)
			)
			(layer "F.Fab")
		)
		(fp_line
			(start -0.12065 0.2794)
			(end -0.12065 0.3048)
			(stroke
				(width 0.1)
				(type default)
			)
			(layer "F.Fab")
		)
		(fp_line
			(start -0.12065 -0.2794)
			(end 0.12065 -0.2794)
			(stroke
				(width 0.1)
				(type default)
			)
			(layer "F.Fab")
		)
		(fp_line
			(start -0.12065 -0.305054)
			(end -0.12065 -0.2794)
			(stroke
				(width 0.1)
				(type default)
			)
			(layer "F.Fab")
		)
		(fp_line
			(start -0.67945 0.3048)
			(end -0.67945 -0.305054)
			(stroke
				(width 0.1)
				(type default)
			)
			(layer "F.Fab")
		)
		(fp_line
			(start -0.67945 -0.305054)
			(end -0.12065 -0.305054)
			(stroke
				(width 0.1)
				(type default)
			)
			(layer "F.Fab")
		)
		(pad "1" smd circle
			(at -0.40005 0 180)
			(size 0 0)
			(layers "F.Cu" "F.Mask" "F.Paste")
			(net "P3V3_OCP_SFF_EN_R")
		)
		(pad "2" smd circle
			(at 0.40005 0 180)
			(size 0 0)
			(layers "F.Cu" "F.Mask" "F.Paste")
			(net "P3V3_AUX")
		)
	)
)
